(kicad_pcb
	(version 20260206)
	(generator "pcbnew")
	(generator_version "10.0")
	(general
		(thickness 1.6)
		(legacy_teardrops no)
	)
	(paper "A4")
	(title_block
		(title "04192023_DAF0TMB3IC0_F0TG_MB_C_brd_V02_OCP.brd")
		(comment 1 "Grand Teton / footprints 6511-6518 of 8354")
	)
	(layers
		(0 "F.Cu" signal "TOP")
		(4 "In1.Cu" signal "GND")
		(6 "In2.Cu" signal "IN1")
		(8 "In3.Cu" signal "GND1")
		(10 "In4.Cu" signal "IN2")
		(12 "In5.Cu" signal "GND2")
		(14 "In6.Cu" signal "IN3")
		(16 "In7.Cu" signal "GND3")
		(18 "In8.Cu" signal "VCC")
		(20 "In9.Cu" signal "VCC1")
		(22 "In10.Cu" signal "GND4")
		(24 "In11.Cu" signal "IN4")
		(26 "In12.Cu" signal "GND5")
		(28 "In13.Cu" signal "IN5")
		(30 "In14.Cu" signal "GND6")
		(32 "In15.Cu" signal "IN6")
		(34 "In16.Cu" signal "GND7")
		(2 "B.Cu" signal "BOTTOM")
		(9 "F.Adhes" user "F.Adhesive")
		(11 "B.Adhes" user "B.Adhesive")
		(13 "F.Paste" user "Package Geometry/Pastemask Top")
		(15 "B.Paste" user "Package Geometry/Pastemask Bottom")
		(5 "F.SilkS" user "Ref Des/Silkscreen Top")
		(7 "B.SilkS" user "Ref Des/Silkscreen Bottom")
		(1 "F.Mask" user "Board Geometry/Soldermask Top")
		(3 "B.Mask" user "Board Geometry/Soldermask Bottom")
		(17 "Dwgs.User" user "User.Drawings")
		(19 "Cmts.User" user "User.Comments")
		(21 "Eco1.User" user "User.Eco1")
		(23 "Eco2.User" user "User.Eco2")
		(25 "Edge.Cuts" user "Board Geometry/Outline")
		(27 "Margin" user)
		(31 "F.CrtYd" user "Package Geometry/Place Bound Top")
		(29 "B.CrtYd" user "Package Geometry/Place Bound Bottom")
		(35 "F.Fab" user "Ref Des/Assembly Top")
		(33 "B.Fab" user "Ref Des/Assembly Bottom")
	)
	(footprint ""
		(layer "B.Cu")
		(at 238.740442 -223.10217 90)
		(property "Reference" "U5"
			(at -1.79324 -2.775458 270)
			(unlocked yes)
			(layer "B.SilkS")
			(effects
				(font
					(size 0.7874 0.5842)
					(thickness 0.1524)
				)
				(justify left mirror)
			)
		)
		(property "Value" ""
			(at 0 0 90)
			(layer "B.Fab")
			(effects
				(font
					(size 1.27 1.27)
				)
				(justify mirror)
			)
		)
		(duplicate_pad_numbers_are_jumpers no)
		(fp_line
			(start 1.463548 -1.549908)
			(end 0.787908 -1.549908)
			(stroke
				(width 0.1524)
				(type default)
			)
			(layer "B.SilkS")
		)
		(fp_line
			(start 0.787908 -1.549908)
			(end 0 -0.762)
			(stroke
				(width 0.1524)
				(type default)
			)
			(layer "B.SilkS")
		)
		(fp_line
			(start -0.762 -1.549908)
			(end -1.463548 -1.549908)
			(stroke
				(width 0.1524)
				(type default)
			)
			(layer "B.SilkS")
		)
		(fp_line
			(start -1.463548 -1.549908)
			(end -1.463548 1.549908)
			(stroke
				(width 0.1524)
				(type default)
			)
			(layer "B.SilkS")
		)
		(fp_line
			(start 0 -0.762)
			(end -0.762 -1.549908)
			(stroke
				(width 0.1524)
				(type default)
			)
			(layer "B.SilkS")
		)
		(fp_line
			(start 1.463548 1.549908)
			(end 1.463548 -1.549908)
			(stroke
				(width 0.1524)
				(type default)
			)
			(layer "B.SilkS")
		)
		(fp_line
			(start -1.463548 1.549908)
			(end 1.463548 1.549908)
			(stroke
				(width 0.1524)
				(type default)
			)
			(layer "B.SilkS")
		)
		(fp_poly
			(pts
				(xy 3.314446 -0.304292) (xy 3.581908 -0.863346) (xy 2.888996 -0.851154)
			)
			(stroke
				(width 0)
				(type default)
			)
			(fill yes)
			(layer "B.SilkS")
		)
		(fp_line
			(start 1.549908 -1.549908)
			(end -1.549908 -1.549908)
			(stroke
				(width 0.1)
				(type default)
			)
			(layer "B.Fab")
		)
		(fp_line
			(start -1.549908 -1.549908)
			(end -1.549908 1.549908)
			(stroke
				(width 0.1)
				(type default)
			)
			(layer "B.Fab")
		)
		(fp_line
			(start 1.549908 1.549908)
			(end 1.549908 -1.549908)
			(stroke
				(width 0.1)
				(type default)
			)
			(layer "B.Fab")
		)
		(fp_line
			(start -1.549908 1.549908)
			(end 1.549908 1.549908)
			(stroke
				(width 0.1)
				(type default)
			)
			(layer "B.Fab")
		)
		(fp_poly
			(pts
				(xy 3.4798 -1.359916) (xy 2.86004 -1.050036) (xy 3.4798 -0.740156)
			)
			(stroke
				(width 0)
				(type default)
			)
			(fill yes)
			(layer "B.Fab")
		)
		(pad "1" smd rect
			(at 2.175002 -1.050036 180)
			(size 0.6096 1.1684)
			(layers "B.Cu" "B.Mask" "B.Paste")
			(net "P3V3_AUX")
		)
		(pad "2" smd rect
			(at 2.175002 -0.32512 180)
			(size 0.4318 1.1684)
			(layers "B.Cu" "B.Mask" "B.Paste")
			(net "SMB_CPU0_CPU1_APML_BUF1_SCL")
		)
		(pad "3" smd rect
			(at 2.175002 0.32512 180)
			(size 0.4318 1.1684)
			(layers "B.Cu" "B.Mask" "B.Paste")
			(net "SMB_CPU0_CPU1_APML_BUF1_SDA")
		)
		(pad "4" smd rect
			(at 2.175002 1.050036 180)
			(size 0.6096 1.1684)
			(layers "B.Cu" "B.Mask" "B.Paste")
			(net "GND")
		)
		(pad "5" smd rect
			(at -2.175002 1.050036 180)
			(size 0.6096 1.1684)
			(layers "B.Cu" "B.Mask" "B.Paste")
			(net "PU_U5_EN")
		)
		(pad "6" smd rect
			(at -2.175002 0.32512 180)
			(size 0.4318 1.1684)
			(layers "B.Cu" "B.Mask" "B.Paste")
			(net "SMB_CPU0_CPU1_APML_BUF1_SDA_R1")
		)
		(pad "7" smd rect
			(at -2.175002 -0.32512 180)
			(size 0.4318 1.1684)
			(layers "B.Cu" "B.Mask" "B.Paste")
			(net "SMB_CPU0_CPU1_APML_BUF1_SCL_R1")
		)
		(pad "8" smd rect
			(at -2.175002 -1.050036 180)
			(size 0.6096 1.1684)
			(layers "B.Cu" "B.Mask" "B.Paste")
			(net "P3V3")
		)
	)
	(footprint ""
		(layer "B.Cu")
		(at 324.336664 -73.534778)
		(property "Reference" "Q79"
			(at 1.4224 -1.768348 0)
			(unlocked yes)
			(layer "B.SilkS")
			(effects
				(font
					(size 0.7874 0.5842)
					(thickness 0.1524)
				)
				(justify left mirror)
			)
		)
		(property "Value" ""
			(at 0 0 0)
			(layer "B.Fab")
			(effects
				(font
					(size 1.27 1.27)
				)
				(justify mirror)
			)
		)
		(duplicate_pad_numbers_are_jumpers no)
		(fp_line
			(start -1.332738 -1.100074)
			(end -1.332738 1.100074)
			(stroke
				(width 0.1524)
				(type default)
			)
			(layer "B.SilkS")
		)
		(fp_line
			(start -1.332738 1.100074)
			(end 1.332738 1.100074)
			(stroke
				(width 0.1524)
				(type default)
			)
			(layer "B.SilkS")
		)
		(fp_line
			(start -0.4826 -1.100074)
			(end -1.332738 -1.100074)
			(stroke
				(width 0.1524)
				(type default)
			)
			(layer "B.SilkS")
		)
		(fp_line
			(start 0 -0.541274)
			(end -0.4826 -1.100074)
			(stroke
				(width 0.1524)
				(type default)
			)
			(layer "B.SilkS")
		)
		(fp_line
			(start 0.4826 -1.100074)
			(end 0 -0.541274)
			(stroke
				(width 0.1524)
				(type default)
			)
			(layer "B.SilkS")
		)
		(fp_line
			(start 1.332738 -1.100074)
			(end 0.4826 -1.100074)
			(stroke
				(width 0.1524)
				(type default)
			)
			(layer "B.SilkS")
		)
		(fp_line
			(start 1.332738 1.100074)
			(end 1.332738 -1.100074)
			(stroke
				(width 0.1524)
				(type default)
			)
			(layer "B.SilkS")
		)
		(fp_poly
			(pts
				(xy 1.334516 -0.649986) (xy 2.036572 -1.001014) (xy 2.036572 -0.298958)
			)
			(stroke
				(width 0)
				(type default)
			)
			(fill yes)
			(layer "B.SilkS")
		)
		(fp_line
			(start -0.674878 -1.100074)
			(end -0.674878 1.100074)
			(stroke
				(width 0.1)
				(type default)
			)
			(layer "B.Fab")
		)
		(fp_line
			(start -0.674878 1.100074)
			(end 0.674878 1.100074)
			(stroke
				(width 0.1)
				(type default)
			)
			(layer "B.Fab")
		)
		(fp_line
			(start 0.674878 -1.100074)
			(end -0.674878 -1.100074)
			(stroke
				(width 0.1)
				(type default)
			)
			(layer "B.Fab")
		)
		(fp_line
			(start 0.674878 1.100074)
			(end 0.674878 -1.100074)
			(stroke
				(width 0.1)
				(type default)
			)
			(layer "B.Fab")
		)
		(fp_poly
			(pts
				(xy 2.2352 -0.298958) (xy 2.2352 -1.001014) (xy 1.533144 -0.649986)
			)
			(stroke
				(width 0)
				(type default)
			)
			(fill yes)
			(layer "B.Fab")
		)
		(pad "1" smd rect
			(at 0.94996 -0.649986 90)
			(size 0.4318 0.508)
			(layers "B.Cu" "B.Mask" "B.Paste")
			(net "GND")
		)
		(pad "2" smd rect
			(at 0.94996 0 90)
			(size 0.4318 0.508)
			(layers "B.Cu" "B.Mask" "B.Paste")
			(net "FM_LED_PWRGD_PVDD33_S5")
		)
		(pad "3" smd rect
			(at 0.94996 0.649986 90)
			(size 0.4318 0.508)
			(layers "B.Cu" "B.Mask" "B.Paste")
			(net "LED_PWRGD_PVDDCR_CPU0_P0_D")
		)
		(pad "4" smd rect
			(at -0.94996 0.649986 90)
			(size 0.4318 0.508)
			(layers "B.Cu" "B.Mask" "B.Paste")
			(net "GND")
		)
		(pad "5" smd rect
			(at -0.94996 0 90)
			(size 0.4318 0.508)
			(layers "B.Cu" "B.Mask" "B.Paste")
			(net "FM_LED_PWRGD_PVDDCR_CPU0_P0")
		)
		(pad "6" smd rect
			(at -0.94996 -0.649986 90)
			(size 0.4318 0.508)
			(layers "B.Cu" "B.Mask" "B.Paste")
			(net "LED_PWRGD_PVDD33_S5_D")
		)
	)
	(footprint ""
		(layer "B.Cu")
		(at 50.978562 -386.766562 90)
		(property "Reference" "C265"
			(at 0 0 90)
			(layer "B.SilkS")
			(hide yes)
			(effects
				(font
					(size 1.27 1.27)
				)
				(justify mirror)
			)
		)
		(property "Value" ""
			(at 0 0 90)
			(layer "B.Fab")
			(effects
				(font
					(size 1.27 1.27)
				)
				(justify mirror)
			)
		)
		(duplicate_pad_numbers_are_jumpers no)
		(fp_line
			(start 0.299974 -0.150114)
			(end -0.299974 -0.150114)
			(stroke
				(width 0.1)
				(type default)
			)
			(layer "B.Fab")
		)
		(fp_line
			(start -0.299974 -0.150114)
			(end -0.299974 0.150114)
			(stroke
				(width 0.1)
				(type default)
			)
			(layer "B.Fab")
		)
		(fp_line
			(start 0.299974 0.150114)
			(end 0.299974 -0.150114)
			(stroke
				(width 0.1)
				(type default)
			)
			(layer "B.Fab")
		)
		(fp_line
			(start -0.299974 0.150114)
			(end 0.299974 0.150114)
			(stroke
				(width 0.1)
				(type default)
			)
			(layer "B.Fab")
		)
		(pad "1" smd rect
			(at 0.2667 0 270)
			(size 0.3048 0.381)
			(layers "B.Cu" "B.Mask" "B.Paste")
			(net "P0V9_CPU1_RT0_2A")
		)
		(pad "2" smd rect
			(at -0.2667 0 270)
			(size 0.3048 0.381)
			(layers "B.Cu" "B.Mask" "B.Paste")
			(net "GND")
		)
	)
	(footprint ""
		(layer "B.Cu")
		(at 409.006294 -395.148562 90)
		(property "Reference" "C780"
			(at 0 0 90)
			(layer "B.SilkS")
			(hide yes)
			(effects
				(font
					(size 1.27 1.27)
				)
				(justify mirror)
			)
		)
		(property "Value" ""
			(at 0 0 90)
			(layer "B.Fab")
			(effects
				(font
					(size 1.27 1.27)
				)
				(justify mirror)
			)
		)
		(duplicate_pad_numbers_are_jumpers no)
		(fp_line
			(start 0.299974 -0.150114)
			(end -0.299974 -0.150114)
			(stroke
				(width 0.1)
				(type default)
			)
			(layer "B.Fab")
		)
		(fp_line
			(start -0.299974 -0.150114)
			(end -0.299974 0.150114)
			(stroke
				(width 0.1)
				(type default)
			)
			(layer "B.Fab")
		)
		(fp_line
			(start 0.299974 0.150114)
			(end 0.299974 -0.150114)
			(stroke
				(width 0.1)
				(type default)
			)
			(layer "B.Fab")
		)
		(fp_line
			(start -0.299974 0.150114)
			(end 0.299974 0.150114)
			(stroke
				(width 0.1)
				(type default)
			)
			(layer "B.Fab")
		)
		(pad "1" smd rect
			(at 0.2667 0 270)
			(size 0.3048 0.381)
			(layers "B.Cu" "B.Mask" "B.Paste")
			(net "P0V9_CPU0_RT_2D")
		)
		(pad "2" smd rect
			(at -0.2667 0 270)
			(size 0.3048 0.381)
			(layers "B.Cu" "B.Mask" "B.Paste")
			(net "GND")
		)
	)
	(footprint ""
		(layer "B.Cu")
		(at 409.159202 -416.899344 90)
		(property "Reference" "C6622"
			(at 0 0 90)
			(layer "B.SilkS")
			(hide yes)
			(effects
				(font
					(size 1.27 1.27)
				)
				(justify mirror)
			)
		)
		(property "Value" ""
			(at 0 0 90)
			(layer "B.Fab")
			(effects
				(font
					(size 1.27 1.27)
				)
				(justify mirror)
			)
		)
		(duplicate_pad_numbers_are_jumpers no)
		(fp_line
			(start 0.299974 -0.150114)
			(end -0.299974 -0.150114)
			(stroke
				(width 0.1)
				(type default)
			)
			(layer "B.Fab")
		)
		(fp_line
			(start -0.299974 -0.150114)
			(end -0.299974 0.150114)
			(stroke
				(width 0.1)
				(type default)
			)
			(layer "B.Fab")
		)
		(fp_line
			(start 0.299974 0.150114)
			(end 0.299974 -0.150114)
			(stroke
				(width 0.1)
				(type default)
			)
			(layer "B.Fab")
		)
		(fp_line
			(start -0.299974 0.150114)
			(end 0.299974 0.150114)
			(stroke
				(width 0.1)
				(type default)
			)
			(layer "B.Fab")
		)
		(pad "1" smd rect
			(at 0.2667 0 270)
			(size 0.3048 0.381)
			(layers "B.Cu" "B.Mask" "B.Paste")
			(net "P5E_CPU0_P3_TX_BUF_C_DN<12>")
		)
		(pad "2" smd rect
			(at -0.2667 0 270)
			(size 0.3048 0.381)
			(layers "B.Cu" "B.Mask" "B.Paste")
			(net "P5E_CPU0_P3_TX_BUF_DN<12>")
		)
	)
	(footprint ""
		(layer "B.Cu")
		(at 361.973114 -267.52931)
		(property "Reference" "C2202"
			(at 0 0 0)
			(layer "B.SilkS")
			(hide yes)
			(effects
				(font
					(size 1.27 1.27)
				)
				(justify mirror)
			)
		)
		(property "Value" ""
			(at 0 0 0)
			(layer "B.Fab")
			(effects
				(font
					(size 1.27 1.27)
				)
				(justify mirror)
			)
		)
		(duplicate_pad_numbers_are_jumpers no)
		(fp_line
			(start -0.7874 -0.4064)
			(end -0.7874 0.4064)
			(stroke
				(width 0.1524)
				(type default)
			)
			(layer "B.SilkS")
		)
		(fp_line
			(start -0.7874 0.4064)
			(end 0.7874 0.4064)
			(stroke
				(width 0.1524)
				(type default)
			)
			(layer "B.SilkS")
		)
		(fp_line
			(start 0.7874 -0.4064)
			(end -0.7874 -0.4064)
			(stroke
				(width 0.1524)
				(type default)
			)
			(layer "B.SilkS")
		)
		(fp_line
			(start 0.7874 0.4064)
			(end 0.7874 -0.4064)
			(stroke
				(width 0.1524)
				(type default)
			)
			(layer "B.SilkS")
		)
		(fp_line
			(start -0.67945 -0.3048)
			(end -0.67945 0.3048)
			(stroke
				(width 0.1)
				(type default)
			)
			(layer "B.Fab")
		)
		(fp_line
			(start -0.67945 0.3048)
			(end -0.120396 0.3048)
			(stroke
				(width 0.1)
				(type default)
			)
			(layer "B.Fab")
		)
		(fp_line
			(start -0.12065 -0.3048)
			(end -0.67945 -0.3048)
			(stroke
				(width 0.1)
				(type default)
			)
			(layer "B.Fab")
		)
		(fp_line
			(start -0.12065 -0.2794)
			(end -0.12065 -0.3048)
			(stroke
				(width 0.1)
				(type default)
			)
			(layer "B.Fab")
		)
		(fp_line
			(start -0.120396 0.2794)
			(end 0.12065 0.2794)
			(stroke
				(width 0.1)
				(type default)
			)
			(layer "B.Fab")
		)
		(fp_line
			(start -0.120396 0.3048)
			(end -0.120396 0.2794)
			(stroke
				(width 0.1)
				(type default)
			)
			(layer "B.Fab")
		)
		(fp_line
			(start 0.12065 -0.305054)
			(end 0.12065 -0.2794)
			(stroke
				(width 0.1)
				(type default)
			)
			(layer "B.Fab")
		)
		(fp_line
			(start 0.12065 -0.2794)
			(end -0.12065 -0.2794)
			(stroke
				(width 0.1)
				(type default)
			)
			(layer "B.Fab")
		)
		(fp_line
			(start 0.12065 0.2794)
			(end 0.12065 0.3048)
			(stroke
				(width 0.1)
				(type default)
			)
			(layer "B.Fab")
		)
		(fp_line
			(start 0.12065 0.3048)
			(end 0.67945 0.3048)
			(stroke
				(width 0.1)
				(type default)
			)
			(layer "B.Fab")
		)
		(fp_line
			(start 0.67945 -0.305054)
			(end 0.12065 -0.305054)
			(stroke
				(width 0.1)
				(type default)
			)
			(layer "B.Fab")
		)
		(fp_line
			(start 0.67945 0.3048)
			(end 0.67945 -0.305054)
			(stroke
				(width 0.1)
				(type default)
			)
			(layer "B.Fab")
		)
		(pad "1" smd circle
			(at 0.40005 0 180)
			(size 0 0)
			(layers "B.Cu" "B.Mask" "B.Paste")
			(net "PVDDCR_CPU1_P0")
		)
		(pad "2" smd circle
			(at -0.40005 0 180)
			(size 0 0)
			(layers "B.Cu" "B.Mask" "B.Paste")
			(net "GND")
		)
	)
	(footprint ""
		(layer "B.Cu")
		(at 234.830874 -326.947022 180)
		(property "Reference" "R1224"
			(at 0 0 0)
			(layer "B.SilkS")
			(hide yes)
			(effects
				(font
					(size 1.27 1.27)
				)
				(justify mirror)
			)
		)
		(property "Value" ""
			(at 0 0 0)
			(layer "B.Fab")
			(effects
				(font
					(size 1.27 1.27)
				)
				(justify mirror)
			)
		)
		(duplicate_pad_numbers_are_jumpers no)
		(fp_line
			(start 0.7874 0.4064)
			(end 0.7874 -0.4064)
			(stroke
				(width 0.1524)
				(type default)
			)
			(layer "B.SilkS")
		)
		(fp_line
			(start 0.7874 -0.4064)
			(end -0.7874 -0.4064)
			(stroke
				(width 0.1524)
				(type default)
			)
			(layer "B.SilkS")
		)
		(fp_line
			(start -0.7874 0.4064)
			(end 0.7874 0.4064)
			(stroke
				(width 0.1524)
				(type default)
			)
			(layer "B.SilkS")
		)
		(fp_line
			(start -0.7874 -0.4064)
			(end -0.7874 0.4064)
			(stroke
				(width 0.1524)
				(type default)
			)
			(layer "B.SilkS")
		)
		(fp_line
			(start 0.67945 0.3048)
			(end 0.67945 -0.305054)
			(stroke
				(width 0.1)
				(type default)
			)
			(layer "B.Fab")
		)
		(fp_line
			(start 0.67945 -0.305054)
			(end 0.12065 -0.305054)
			(stroke
				(width 0.1)
				(type default)
			)
			(layer "B.Fab")
		)
		(fp_line
			(start 0.12065 0.3048)
			(end 0.67945 0.3048)
			(stroke
				(width 0.1)
				(type default)
			)
			(layer "B.Fab")
		)
		(fp_line
			(start 0.12065 0.2794)
			(end 0.12065 0.3048)
			(stroke
				(width 0.1)
				(type default)
			)
			(layer "B.Fab")
		)
		(fp_line
			(start 0.12065 -0.2794)
			(end -0.12065 -0.2794)
			(stroke
				(width 0.1)
				(type default)
			)
			(layer "B.Fab")
		)
		(fp_line
			(start 0.12065 -0.305054)
			(end 0.12065 -0.2794)
			(stroke
				(width 0.1)
				(type default)
			)
			(layer "B.Fab")
		)
		(fp_line
			(start -0.120396 0.3048)
			(end -0.120396 0.2794)
			(stroke
				(width 0.1)
				(type default)
			)
			(layer "B.Fab")
		)
		(fp_line
			(start -0.120396 0.2794)
			(end 0.12065 0.2794)
			(stroke
				(width 0.1)
				(type default)
			)
			(layer "B.Fab")
		)
		(fp_line
			(start -0.12065 -0.2794)
			(end -0.12065 -0.3048)
			(stroke
				(width 0.1)
				(type default)
			)
			(layer "B.Fab")
		)
		(fp_line
			(start -0.12065 -0.3048)
			(end -0.67945 -0.3048)
			(stroke
				(width 0.1)
				(type default)
			)
			(layer "B.Fab")
		)
		(fp_line
			(start -0.67945 0.3048)
			(end -0.120396 0.3048)
			(stroke
				(width 0.1)
				(type default)
			)
			(layer "B.Fab")
		)
		(fp_line
			(start -0.67945 -0.3048)
			(end -0.67945 0.3048)
			(stroke
				(width 0.1)
				(type default)
			)
			(layer "B.Fab")
		)
		(pad "1" smd circle
			(at 0.40005 0)
			(size 0 0)
			(layers "B.Cu" "B.Mask" "B.Paste")
			(net "PVDD_33_S5_ADC")
		)
		(pad "2" smd circle
			(at -0.40005 0)
			(size 0 0)
			(layers "B.Cu" "B.Mask" "B.Paste")
			(net "GND")
		)
	)
	(footprint ""
		(layer "B.Cu")
		(at 94.30639 -386.766562 90)
		(property "Reference" "C314"
			(at 0 0 90)
			(layer "B.SilkS")
			(hide yes)
			(effects
				(font
					(size 1.27 1.27)
				)
				(justify mirror)
			)
		)
		(property "Value" ""
			(at 0 0 90)
			(layer "B.Fab")
			(effects
				(font
					(size 1.27 1.27)
				)
				(justify mirror)
			)
		)
		(duplicate_pad_numbers_are_jumpers no)
		(fp_line
			(start 0.299974 -0.150114)
			(end -0.299974 -0.150114)
			(stroke
				(width 0.1)
				(type default)
			)
			(layer "B.Fab")
		)
		(fp_line
			(start -0.299974 -0.150114)
			(end -0.299974 0.150114)
			(stroke
				(width 0.1)
				(type default)
			)
			(layer "B.Fab")
		)
		(fp_line
			(start 0.299974 0.150114)
			(end 0.299974 -0.150114)
			(stroke
				(width 0.1)
				(type default)
			)
			(layer "B.Fab")
		)
		(fp_line
			(start -0.299974 0.150114)
			(end 0.299974 0.150114)
			(stroke
				(width 0.1)
				(type default)
			)
			(layer "B.Fab")
		)
		(pad "1" smd rect
			(at 0.2667 0 270)
			(size 0.3048 0.381)
			(layers "B.Cu" "B.Mask" "B.Paste")
			(net "P0V9_CPU1_RT1_2A")
		)
		(pad "2" smd rect
			(at -0.2667 0 270)
			(size 0.3048 0.381)
			(layers "B.Cu" "B.Mask" "B.Paste")
			(net "GND")
		)
	)
)
